FILE_TYPE = MACRO_DRAWING;
SET COLOR_WIRE YELLOW;
SET COLOR_PROP ORANGE;
SET COLOR_DOT WHITE;
SET COLOR_ARC YELLOW;
SET COLOR_BODY GREEN;
SET COLOR_NOTE PURPLE;
SET PROP_DISPLAY VALUE;
SET PAGE_NUMBER P186;
FORCEADD UNIVERSAL_POWER..1
(-3475 1525);
FORCEPROP 3 LASTPIN (-3475 1475) SIG_NAME P3V3_AUX\g
J 0
(-3465 1485);
DISPLAY 0.659574 (-3465 1485);
PAINT MONO (-3465 1485);
DISPLAY INVISIBLE (-3465 1485);
FORCEPROP 1 LAST HDL_POWER P3V3_AUX
J 1
(-3475 1575);
DISPLAY 0.872340 (-3475 1575);
PAINT GREEN (-3475 1575);
FORCEPROP 1 LAST PATH I10
J 0
(-3425 1550);
DISPLAY 0.872340 (-3425 1550);
PAINT AQUA (-3425 1550);
DISPLAY INVISIBLE (-3425 1550);
FORCEPROP 2 LAST CDS_LIB logical_power
J 0
(-3475 1525);
PAINT MONO (-3475 1525);
DISPLAY INVISIBLE (-3475 1525);
FORCEADD Q_RES..2
(-3475 1275);
FORCEPROP 1 LAST PART_NUMBER CS21002FB06
J 0
(-3435 1150);
DISPLAY 0.787234 (-3435 1150);
DISPLAY INVISIBLE (-3435 1150);
FORCEPROP 1 LAST WATTAGE 1/16W
J 0
(-3435 1250);
DISPLAY 0.787234 (-3435 1250);
FORCEPROP 1 LAST MATERIAL EMPTY
J 0
(-3435 1200);
DISPLAY 0.787234 (-3435 1200);
PAINT RED (-3435 1200);
FORCEPROP 1 LAST PACK_TYPE 0402LF
J 0
(-3435 1100);
DISPLAY 0.787234 (-3435 1100);
FORCEPROP 1 LAST VALUE 1K
J 0
(-3430 1350);
DISPLAY 0.787234 (-3430 1350);
FORCEPROP 1 LAST TOLERANCE 1%
J 0
(-3430 1300);
DISPLAY 0.787234 (-3430 1300);
FORCEPROP 1 LAST $LOCATION R367
J 0
(-3430 1400);
DISPLAY 0.978723 (-3430 1400);
FORCEPROP 1 LASTPIN (-3475 1375) $PN 1
J 0
(-3470 1337);
DISPLAY 0.787234 (-3470 1337);
FORCEPROP 1 LASTPIN (-3475 1175) $PN 2
J 0
(-3470 1185);
DISPLAY 0.787234 (-3470 1185);
FORCEPROP 1 LAST PATH I11
J 0
(-3425 1450);
DISPLAY 0.978723 (-3425 1450);
PAINT WHITE (-3425 1450);
DISPLAY INVISIBLE (-3425 1450);
FORCEPROP 2 LAST CDS_LIB pure_quanta
J 0
(-3475 1275);
PAINT MONO (-3475 1275);
DISPLAY INVISIBLE (-3475 1275);
FORCEPROP 2 LAST CDS_LOCATION R367
J 0
(-3425 1500);
DISPLAY 1.021277 (-3425 1500);
DISPLAY INVISIBLE (-3425 1500);
FORCEPROP 2 LAST $SEC 1
J 0
(-3425 1500);
DISPLAY 0.680851 (-3425 1500);
PAINT MONO (-3425 1500);
DISPLAY INVISIBLE (-3425 1500);
FORCEPROP 2 LAST CDS_SEC 1
J 0
(-3425 1500);
DISPLAY 1.021277 (-3425 1500);
DISPLAY INVISIBLE (-3425 1500);
FORCEADD OFFPAGE..2
(-2225 -1050);
FORCEPROP 2 LAST $XR1 183 
J 0
(-1916 -1050);
DISPLAY 0.638298 (-1916 -1050);
PAINT MONO (-1916 -1050);
FORCEPROP 2 LAST $XR0 215 
J 0
(-2036 -1050);
DISPLAY 0.638298 (-2036 -1050);
PAINT MONO (-2036 -1050);
FORCEPROP 2 LAST PATH I14
J 0
(-2050 -975);
DISPLAY 1.021277 (-2050 -975);
DISPLAY INVISIBLE (-2050 -975);
FORCEPROP 1 LAST COMMENT_BODY TRUE
J 0
(-2270 -1145);
DISPLAY 0.872340 (-2270 -1145);
PAINT GREEN (-2270 -1145);
DISPLAY INVISIBLE (-2270 -1145);
FORCEPROP 1 LAST OFFPAGE TRUE
J 0
(-1900 -1175);
DISPLAY 0.872340 (-1900 -1175);
DISPLAY INVISIBLE (-1900 -1175);
FORCEPROP 2 LAST CDS_LIB standard
J 0
(-2225 -1050);
PAINT MONO (-2225 -1050);
DISPLAY INVISIBLE (-2225 -1050);
FORCEADD UNIVERSAL_POWER..1
(-3475 -550);
FORCEPROP 3 LASTPIN (-3475 -600) SIG_NAME P3V3_AUX\g
J 0
(-3465 -590);
DISPLAY 0.659574 (-3465 -590);
PAINT MONO (-3465 -590);
DISPLAY INVISIBLE (-3465 -590);
FORCEPROP 1 LAST HDL_POWER P3V3_AUX
J 1
(-3475 -500);
DISPLAY 0.872340 (-3475 -500);
PAINT GREEN (-3475 -500);
FORCEPROP 1 LAST PATH I15
J 0
(-3425 -525);
DISPLAY 0.872340 (-3425 -525);
PAINT AQUA (-3425 -525);
DISPLAY INVISIBLE (-3425 -525);
FORCEPROP 2 LAST CDS_LIB logical_power
J 0
(-3475 -550);
PAINT MONO (-3475 -550);
DISPLAY INVISIBLE (-3475 -550);
FORCEADD Q_RES..2
(-3475 -800);
FORCEPROP 1 LAST PART_NUMBER CS21002FB06
J 0
(-3435 -925);
DISPLAY 0.787234 (-3435 -925);
DISPLAY INVISIBLE (-3435 -925);
FORCEPROP 1 LAST TOLERANCE 1%
J 0
(-3430 -775);
DISPLAY 0.787234 (-3430 -775);
FORCEPROP 1 LAST MATERIAL CHIP
J 0
(-3435 -875);
DISPLAY 0.787234 (-3435 -875);
FORCEPROP 1 LAST PACK_TYPE 0402LF
J 0
(-3435 -975);
DISPLAY 0.787234 (-3435 -975);
FORCEPROP 1 LAST WATTAGE 1/16W
J 0
(-3435 -825);
DISPLAY 0.787234 (-3435 -825);
FORCEPROP 1 LAST VALUE 1K
J 0
(-3430 -725);
DISPLAY 0.787234 (-3430 -725);
FORCEPROP 1 LAST $LOCATION R369
J 0
(-3430 -675);
DISPLAY 0.978723 (-3430 -675);
FORCEPROP 1 LASTPIN (-3475 -700) $PN 1
J 0
(-3470 -738);
DISPLAY 0.787234 (-3470 -738);
FORCEPROP 1 LASTPIN (-3475 -900) $PN 2
J 0
(-3470 -890);
DISPLAY 0.787234 (-3470 -890);
FORCEPROP 1 LAST PATH I16
J 0
(-3425 -625);
DISPLAY 0.978723 (-3425 -625);
PAINT WHITE (-3425 -625);
DISPLAY INVISIBLE (-3425 -625);
FORCEPROP 2 LAST CDS_LIB pure_quanta
J 0
(-3475 -800);
PAINT MONO (-3475 -800);
DISPLAY INVISIBLE (-3475 -800);
FORCEPROP 2 LAST CDS_LOCATION R369
J 0
(-3425 -575);
DISPLAY 1.021277 (-3425 -575);
DISPLAY INVISIBLE (-3425 -575);
FORCEPROP 2 LAST $SEC 1
J 0
(-3425 -575);
DISPLAY 0.680851 (-3425 -575);
PAINT MONO (-3425 -575);
DISPLAY INVISIBLE (-3425 -575);
FORCEPROP 2 LAST CDS_SEC 1
J 0
(-3425 -575);
DISPLAY 1.021277 (-3425 -575);
DISPLAY INVISIBLE (-3425 -575);
FORCEADD OFFPAGE..2
(900 3000);
FORCEPROP 2 LAST $XR0 183 
J 0
(1089 3000);
DISPLAY 0.638298 (1089 3000);
PAINT MONO (1089 3000);
FORCEPROP 2 LAST PATH I41
J 0
(1075 3075);
DISPLAY 1.021277 (1075 3075);
DISPLAY INVISIBLE (1075 3075);
FORCEPROP 1 LAST COMMENT_BODY TRUE
J 0
(855 2905);
DISPLAY 0.872340 (855 2905);
PAINT GREEN (855 2905);
DISPLAY INVISIBLE (855 2905);
FORCEPROP 1 LAST OFFPAGE TRUE
J 0
(1225 2875);
DISPLAY 0.872340 (1225 2875);
DISPLAY INVISIBLE (1225 2875);
FORCEPROP 2 LAST CDS_LIB standard
J 0
(900 3000);
PAINT MONO (900 3000);
DISPLAY INVISIBLE (900 3000);
FORCEADD UNIVERSAL_POWER..1
(-350 3550);
FORCEPROP 3 LASTPIN (-350 3500) SIG_NAME P3V3_AUX\g
J 0
(-340 3510);
DISPLAY 0.659574 (-340 3510);
PAINT MONO (-340 3510);
DISPLAY INVISIBLE (-340 3510);
FORCEPROP 1 LAST HDL_POWER P3V3_AUX
J 1
(-350 3600);
DISPLAY 0.872340 (-350 3600);
PAINT GREEN (-350 3600);
FORCEPROP 1 LAST PATH I44
J 0
(-300 3575);
DISPLAY 0.872340 (-300 3575);
PAINT AQUA (-300 3575);
DISPLAY INVISIBLE (-300 3575);
FORCEPROP 2 LAST CDS_LIB logical_power
J 0
(-350 3550);
PAINT MONO (-350 3550);
DISPLAY INVISIBLE (-350 3550);
FORCEADD Q_RES..2
(-350 3300);
FORCEPROP 1 LAST PART_NUMBER CS21002FB06
J 0
(-310 3175);
DISPLAY 0.638298 (-310 3175);
DISPLAY INVISIBLE (-310 3175);
FORCEPROP 1 LAST TOLERANCE 1%
J 0
(-305 3325);
DISPLAY 0.787234 (-305 3325);
FORCEPROP 1 LAST VALUE 1K
J 0
(-305 3375);
DISPLAY 0.787234 (-305 3375);
FORCEPROP 1 LAST MATERIAL EMPTY
J 0
(-310 3225);
DISPLAY 0.787234 (-310 3225);
FORCEPROP 1 LAST WATTAGE 1/16W
J 0
(-310 3275);
DISPLAY 0.787234 (-310 3275);
FORCEPROP 1 LAST PACK_TYPE 0402LF
J 0
(-310 3125);
DISPLAY 0.787234 (-310 3125);
FORCEPROP 1 LAST $LOCATION R371
J 0
(-305 3425);
DISPLAY 0.978723 (-305 3425);
FORCEPROP 1 LASTPIN (-350 3400) $PN 1
J 0
(-345 3362);
DISPLAY 0.787234 (-345 3362);
FORCEPROP 1 LASTPIN (-350 3200) $PN 2
J 0
(-345 3210);
DISPLAY 0.787234 (-345 3210);
FORCEPROP 1 LAST PATH I45
J 0
(-300 3475);
DISPLAY 0.978723 (-300 3475);
PAINT WHITE (-300 3475);
DISPLAY INVISIBLE (-300 3475);
FORCEPROP 2 LAST CDS_LIB pure_quanta
J 0
(-350 3300);
PAINT MONO (-350 3300);
DISPLAY INVISIBLE (-350 3300);
FORCEPROP 2 LAST CDS_LOCATION R371
J 0
(-300 3525);
DISPLAY 1.021277 (-300 3525);
DISPLAY INVISIBLE (-300 3525);
FORCEPROP 2 LAST $SEC 1
J 0
(-300 3525);
DISPLAY 0.680851 (-300 3525);
PAINT MONO (-300 3525);
DISPLAY INVISIBLE (-300 3525);
FORCEPROP 2 LAST CDS_SEC 1
J 0
(-300 3525);
DISPLAY 1.021277 (-300 3525);
DISPLAY INVISIBLE (-300 3525);
FORCEADD Q_RES..2
(-350 2775);
FORCEPROP 1 LAST PART_NUMBER CS31002FB08
J 0
(-310 2650);
DISPLAY 0.787234 (-310 2650);
DISPLAY INVISIBLE (-310 2650);
FORCEPROP 1 LAST WATTAGE 1/16W
J 0
(-310 2750);
DISPLAY 0.787234 (-310 2750);
FORCEPROP 1 LAST TOLERANCE 1%
J 0
(-305 2800);
DISPLAY 0.787234 (-305 2800);
FORCEPROP 1 LAST PACK_TYPE 0402LF
J 0
(-310 2600);
DISPLAY 0.787234 (-310 2600);
FORCEPROP 1 LAST VALUE 10K
J 0
(-305 2850);
DISPLAY 0.787234 (-305 2850);
FORCEPROP 1 LAST MATERIAL CHIP
J 0
(-310 2700);
DISPLAY 0.787234 (-310 2700);
FORCEPROP 1 LAST $LOCATION R372
J 0
(-305 2900);
DISPLAY 0.978723 (-305 2900);
FORCEPROP 1 LASTPIN (-350 2875) $PN 1
J 0
(-345 2837);
DISPLAY 0.787234 (-345 2837);
FORCEPROP 1 LASTPIN (-350 2675) $PN 2
J 0
(-345 2685);
DISPLAY 0.787234 (-345 2685);
FORCEPROP 1 LAST PATH I46
J 0
(-300 2950);
DISPLAY 0.978723 (-300 2950);
PAINT WHITE (-300 2950);
DISPLAY INVISIBLE (-300 2950);
FORCEPROP 2 LAST CDS_LIB pure_quanta
J 0
(-350 2775);
PAINT MONO (-350 2775);
DISPLAY INVISIBLE (-350 2775);
FORCEPROP 2 LAST CDS_LOCATION R372
J 0
(-300 3000);
DISPLAY 1.021277 (-300 3000);
DISPLAY INVISIBLE (-300 3000);
FORCEPROP 2 LAST $SEC 1
J 0
(-300 3000);
DISPLAY 0.680851 (-300 3000);
PAINT MONO (-300 3000);
DISPLAY INVISIBLE (-300 3000);
FORCEPROP 2 LAST CDS_SEC 1
J 0
(-300 3000);
DISPLAY 1.021277 (-300 3000);
DISPLAY INVISIBLE (-300 3000);
FORCEADD UNIVERSAL_GND..1
(-350 2550);
FORCEPROP 3 LASTPIN (-350 2600) SIG_NAME GND\g
J 0
(-340 2610);
DISPLAY 0.659574 (-340 2610);
PAINT MONO (-340 2610);
DISPLAY INVISIBLE (-340 2610);
FORCEPROP 2 LAST ROOM IO_SLOT
J 1
(-575 2625);
DISPLAY 0.744681 (-575 2625);
DISPLAY INVISIBLE (-575 2625);
FORCEPROP 1 LAST PATH I47
J 0
(-275 2550);
DISPLAY 0.872340 (-275 2550);
PAINT AQUA (-275 2550);
DISPLAY INVISIBLE (-275 2550);
FORCEPROP 1 LAST HDL_POWER GND
J 1
(-325 2475);
DISPLAY 0.872340 (-325 2475);
PAINT GREEN (-325 2475);
DISPLAY INVISIBLE (-325 2475);
FORCEPROP 2 LAST CDS_LIB logical_power
J 0
(-350 2550);
PAINT MONO (-350 2550);
DISPLAY INVISIBLE (-350 2550);
FORCEADD UNIVERSAL_POWER..1
(-350 -550);
FORCEPROP 3 LASTPIN (-350 -600) SIG_NAME P3V3_AUX\g
J 0
(-340 -590);
DISPLAY 0.659574 (-340 -590);
PAINT MONO (-340 -590);
DISPLAY INVISIBLE (-340 -590);
FORCEPROP 1 LAST HDL_POWER P3V3_AUX
J 1
(-350 -500);
DISPLAY 0.872340 (-350 -500);
PAINT GREEN (-350 -500);
FORCEPROP 1 LAST PATH I58
J 0
(-300 -525);
DISPLAY 0.872340 (-300 -525);
PAINT AQUA (-300 -525);
DISPLAY INVISIBLE (-300 -525);
FORCEPROP 2 LAST CDS_LIB logical_power
J 0
(-350 -550);
PAINT MONO (-350 -550);
DISPLAY INVISIBLE (-350 -550);
FORCEADD OFFPAGE..2
(900 -1050);
FORCEPROP 2 LAST $XR0 185 
J 0
(1089 -1050);
DISPLAY 0.638298 (1089 -1050);
PAINT MONO (1089 -1050);
FORCEPROP 2 LAST PATH I59
J 0
(1075 -975);
DISPLAY 1.021277 (1075 -975);
DISPLAY INVISIBLE (1075 -975);
FORCEPROP 1 LAST COMMENT_BODY TRUE
J 0
(855 -1145);
DISPLAY 0.872340 (855 -1145);
PAINT GREEN (855 -1145);
DISPLAY INVISIBLE (855 -1145);
FORCEPROP 1 LAST OFFPAGE TRUE
J 0
(1225 -1175);
DISPLAY 0.872340 (1225 -1175);
DISPLAY INVISIBLE (1225 -1175);
FORCEPROP 2 LAST CDS_LIB standard
J 0
(900 -1050);
PAINT MONO (900 -1050);
DISPLAY INVISIBLE (900 -1050);
FORCEADD Q_RES..2
(-350 -800);
FORCEPROP 1 LAST PART_NUMBER CS21002FB06
J 0
(-310 -925);
DISPLAY 0.787234 (-310 -925);
DISPLAY INVISIBLE (-310 -925);
FORCEPROP 1 LAST TOLERANCE 1%
J 0
(-305 -775);
DISPLAY 0.787234 (-305 -775);
FORCEPROP 1 LAST VALUE 1K
J 0
(-305 -725);
DISPLAY 0.787234 (-305 -725);
FORCEPROP 1 LAST WATTAGE 1/16W
J 0
(-310 -825);
DISPLAY 0.787234 (-310 -825);
FORCEPROP 1 LAST PACK_TYPE 0402LF
J 0
(-310 -975);
DISPLAY 0.787234 (-310 -975);
FORCEPROP 1 LAST MATERIAL EMPTY
J 0
(-310 -875);
DISPLAY 0.787234 (-310 -875);
PAINT RED (-310 -875);
FORCEPROP 1 LAST $LOCATION R374
J 0
(-305 -675);
DISPLAY 0.978723 (-305 -675);
FORCEPROP 1 LASTPIN (-350 -700) $PN 1
J 0
(-345 -738);
DISPLAY 0.787234 (-345 -738);
FORCEPROP 1 LASTPIN (-350 -900) $PN 2
J 0
(-345 -890);
DISPLAY 0.787234 (-345 -890);
FORCEPROP 1 LAST PATH I60
J 0
(-300 -625);
DISPLAY 0.978723 (-300 -625);
PAINT WHITE (-300 -625);
DISPLAY INVISIBLE (-300 -625);
FORCEPROP 2 LAST CDS_LIB pure_quanta
J 0
(-350 -800);
PAINT MONO (-350 -800);
DISPLAY INVISIBLE (-350 -800);
FORCEPROP 2 LAST CDS_LOCATION R374
J 0
(-300 -575);
DISPLAY 1.021277 (-300 -575);
DISPLAY INVISIBLE (-300 -575);
FORCEPROP 2 LAST $SEC 1
J 0
(-300 -575);
DISPLAY 0.680851 (-300 -575);
PAINT MONO (-300 -575);
DISPLAY INVISIBLE (-300 -575);
FORCEPROP 2 LAST CDS_SEC 1
J 0
(-300 -575);
DISPLAY 1.021277 (-300 -575);
DISPLAY INVISIBLE (-300 -575);
FORCEADD Q_RES..2
(-350 -1275);
FORCEPROP 1 LAST PART_NUMBER CS31002FB08
J 0
(-310 -1400);
DISPLAY 0.787234 (-310 -1400);
DISPLAY INVISIBLE (-310 -1400);
FORCEPROP 1 LAST VALUE 10K
J 0
(-305 -1200);
DISPLAY 0.787234 (-305 -1200);
FORCEPROP 1 LAST WATTAGE 1/16W
J 0
(-310 -1300);
DISPLAY 0.787234 (-310 -1300);
FORCEPROP 1 LAST MATERIAL CHIP
J 0
(-310 -1350);
DISPLAY 0.787234 (-310 -1350);
FORCEPROP 1 LAST PACK_TYPE 0402LF
J 0
(-310 -1450);
DISPLAY 0.787234 (-310 -1450);
FORCEPROP 1 LAST TOLERANCE 1%
J 0
(-305 -1250);
DISPLAY 0.787234 (-305 -1250);
FORCEPROP 1 LAST $LOCATION R375
J 0
(-305 -1150);
DISPLAY 0.978723 (-305 -1150);
FORCEPROP 1 LASTPIN (-350 -1175) $PN 1
J 0
(-345 -1213);
DISPLAY 0.787234 (-345 -1213);
FORCEPROP 1 LASTPIN (-350 -1375) $PN 2
J 0
(-345 -1365);
DISPLAY 0.787234 (-345 -1365);
FORCEPROP 1 LAST PATH I61
J 0
(-300 -1100);
DISPLAY 0.978723 (-300 -1100);
PAINT WHITE (-300 -1100);
DISPLAY INVISIBLE (-300 -1100);
FORCEPROP 2 LAST CDS_LIB pure_quanta
J 0
(-350 -1275);
PAINT MONO (-350 -1275);
DISPLAY INVISIBLE (-350 -1275);
FORCEPROP 2 LAST CDS_LOCATION R375
J 0
(-300 -1050);
DISPLAY 1.021277 (-300 -1050);
DISPLAY INVISIBLE (-300 -1050);
FORCEPROP 2 LAST $SEC 1
J 0
(-300 -1050);
DISPLAY 0.680851 (-300 -1050);
PAINT MONO (-300 -1050);
DISPLAY INVISIBLE (-300 -1050);
FORCEPROP 2 LAST CDS_SEC 1
J 0
(-300 -1050);
DISPLAY 1.021277 (-300 -1050);
DISPLAY INVISIBLE (-300 -1050);
FORCEADD UNIVERSAL_GND..1
(-350 -1500);
FORCEPROP 3 LASTPIN (-350 -1450) SIG_NAME GND\g
J 0
(-340 -1440);
DISPLAY 0.659574 (-340 -1440);
PAINT MONO (-340 -1440);
DISPLAY INVISIBLE (-340 -1440);
FORCEPROP 2 LAST ROOM IO_SLOT
J 1
(-575 -1425);
DISPLAY 0.744681 (-575 -1425);
DISPLAY INVISIBLE (-575 -1425);
FORCEPROP 1 LAST PATH I62
J 0
(-275 -1500);
DISPLAY 0.872340 (-275 -1500);
PAINT AQUA (-275 -1500);
DISPLAY INVISIBLE (-275 -1500);
FORCEPROP 1 LAST HDL_POWER GND
J 1
(-325 -1575);
DISPLAY 0.872340 (-325 -1575);
PAINT GREEN (-325 -1575);
DISPLAY INVISIBLE (-325 -1575);
FORCEPROP 2 LAST CDS_LIB logical_power
J 0
(-350 -1500);
PAINT MONO (-350 -1500);
DISPLAY INVISIBLE (-350 -1500);
FORCEADD OFFPAGE..2
(4075 3000);
FORCEPROP 2 LAST $XR1 185 
J 0
(4384 3000);
DISPLAY 0.638298 (4384 3000);
PAINT MONO (4384 3000);
FORCEPROP 2 LAST $XR0 131 
J 0
(4264 3000);
DISPLAY 0.638298 (4264 3000);
PAINT MONO (4264 3000);
FORCEPROP 2 LAST PATH I64
J 0
(4250 3075);
DISPLAY 1.021277 (4250 3075);
DISPLAY INVISIBLE (4250 3075);
FORCEPROP 1 LAST COMMENT_BODY TRUE
J 0
(4030 2905);
DISPLAY 0.872340 (4030 2905);
PAINT GREEN (4030 2905);
DISPLAY INVISIBLE (4030 2905);
FORCEPROP 1 LAST OFFPAGE TRUE
J 0
(4400 2875);
DISPLAY 0.872340 (4400 2875);
DISPLAY INVISIBLE (4400 2875);
FORCEPROP 2 LAST CDS_LIB standard
J 0
(4075 3000);
PAINT MONO (4075 3000);
DISPLAY INVISIBLE (4075 3000);
FORCEADD UNIVERSAL_POWER..1
(2825 3500);
FORCEPROP 3 LASTPIN (2825 3450) SIG_NAME P3V3_AUX\g
J 0
(2835 3460);
DISPLAY 0.659574 (2835 3460);
PAINT MONO (2835 3460);
DISPLAY INVISIBLE (2835 3460);
FORCEPROP 1 LAST HDL_POWER P3V3_AUX
J 1
(2825 3550);
DISPLAY 0.872340 (2825 3550);
PAINT GREEN (2825 3550);
FORCEPROP 1 LAST PATH I65
J 0
(2875 3525);
DISPLAY 0.872340 (2875 3525);
PAINT AQUA (2875 3525);
DISPLAY INVISIBLE (2875 3525);
FORCEPROP 2 LAST CDS_LIB logical_power
J 0
(2825 3500);
PAINT MONO (2825 3500);
DISPLAY INVISIBLE (2825 3500);
FORCEADD Q_RES..2
(2825 3250);
FORCEPROP 1 LAST PART_NUMBER CS32002FB06
J 0
(2865 3125);
DISPLAY 0.638298 (2865 3125);
DISPLAY INVISIBLE (2865 3125);
FORCEPROP 1 LAST MATERIAL CHIP
J 0
(2865 3175);
DISPLAY 0.787234 (2865 3175);
FORCEPROP 1 LAST WATTAGE 1/16W
J 0
(2865 3225);
DISPLAY 0.787234 (2865 3225);
FORCEPROP 1 LAST VALUE 20K
J 0
(2870 3325);
DISPLAY 0.787234 (2870 3325);
FORCEPROP 1 LAST PACK_TYPE 0402LF
J 0
(2865 3075);
DISPLAY 0.787234 (2865 3075);
FORCEPROP 1 LAST TOLERANCE 1%
J 0
(2870 3275);
DISPLAY 0.787234 (2870 3275);
FORCEPROP 1 LAST $LOCATION R502
J 0
(2870 3375);
DISPLAY 0.978723 (2870 3375);
FORCEPROP 1 LASTPIN (2825 3350) $PN 1
J 0
(2830 3312);
DISPLAY 0.787234 (2830 3312);
FORCEPROP 1 LASTPIN (2825 3150) $PN 2
J 0
(2830 3160);
DISPLAY 0.787234 (2830 3160);
FORCEPROP 2 LAST CDS_LIB pure_quanta
J 0
(2825 3250);
PAINT MONO (2825 3250);
DISPLAY INVISIBLE (2825 3250);
FORCEPROP 1 LAST PATH I68
J 0
(2875 3425);
DISPLAY 0.978723 (2875 3425);
PAINT WHITE (2875 3425);
DISPLAY INVISIBLE (2875 3425);
FORCEPROP 2 LAST CDS_LOCATION R502
J 0
(2875 3475);
DISPLAY 1.021277 (2875 3475);
DISPLAY INVISIBLE (2875 3475);
FORCEPROP 2 LAST $SEC 1
J 0
(2875 3475);
DISPLAY 0.680851 (2875 3475);
PAINT MONO (2875 3475);
DISPLAY INVISIBLE (2875 3475);
FORCEPROP 2 LAST CDS_SEC 1
J 0
(2875 3475);
DISPLAY 1.021277 (2875 3475);
DISPLAY INVISIBLE (2875 3475);
FORCEADD OFFPAGE..2
(4075 1000);
FORCEPROP 2 LAST $XR1 223 
J 0
(4384 1000);
DISPLAY 0.638298 (4384 1000);
PAINT MONO (4384 1000);
FORCEPROP 2 LAST $XR0 183 
J 0
(4264 1000);
DISPLAY 0.638298 (4264 1000);
PAINT MONO (4264 1000);
FORCEPROP 2 LAST PATH I72
J 0
(4250 1075);
DISPLAY 1.021277 (4250 1075);
DISPLAY INVISIBLE (4250 1075);
FORCEPROP 1 LAST COMMENT_BODY TRUE
J 0
(4030 905);
DISPLAY 0.872340 (4030 905);
PAINT GREEN (4030 905);
DISPLAY INVISIBLE (4030 905);
FORCEPROP 1 LAST OFFPAGE TRUE
J 0
(4400 875);
DISPLAY 0.872340 (4400 875);
DISPLAY INVISIBLE (4400 875);
FORCEPROP 2 LAST CDS_LIB standard
J 0
(4075 1000);
PAINT MONO (4075 1000);
DISPLAY INVISIBLE (4075 1000);
FORCEADD UNIVERSAL_POWER..1
(2800 1500);
FORCEPROP 3 LASTPIN (2800 1450) SIG_NAME P3V3_AUX\g
J 0
(2810 1460);
DISPLAY 0.659574 (2810 1460);
PAINT MONO (2810 1460);
DISPLAY INVISIBLE (2810 1460);
FORCEPROP 1 LAST HDL_POWER P3V3_AUX
J 1
(2800 1550);
DISPLAY 0.872340 (2800 1550);
PAINT GREEN (2800 1550);
FORCEPROP 1 LAST PATH I73
J 0
(2850 1525);
DISPLAY 0.872340 (2850 1525);
PAINT AQUA (2850 1525);
DISPLAY INVISIBLE (2850 1525);
FORCEPROP 2 LAST CDS_LIB logical_power
J 0
(2800 1500);
PAINT MONO (2800 1500);
DISPLAY INVISIBLE (2800 1500);
FORCEADD UNIVERSAL_GND..1
(2800 550);
FORCEPROP 3 LASTPIN (2800 600) SIG_NAME GND\g
J 0
(2810 610);
DISPLAY 0.659574 (2810 610);
PAINT MONO (2810 610);
DISPLAY INVISIBLE (2810 610);
FORCEPROP 2 LAST ROOM IO_SLOT
J 1
(2575 625);
DISPLAY 0.744681 (2575 625);
DISPLAY INVISIBLE (2575 625);
FORCEPROP 1 LAST PATH I74
J 0
(2875 550);
DISPLAY 0.872340 (2875 550);
PAINT AQUA (2875 550);
DISPLAY INVISIBLE (2875 550);
FORCEPROP 1 LAST HDL_POWER GND
J 1
(2825 475);
DISPLAY 0.872340 (2825 475);
PAINT GREEN (2825 475);
DISPLAY INVISIBLE (2825 475);
FORCEPROP 2 LAST CDS_LIB logical_power
J 0
(2800 550);
PAINT MONO (2800 550);
DISPLAY INVISIBLE (2800 550);
FORCEADD Q_RES..2
(2800 775);
FORCEPROP 1 LAST PART_NUMBER CS21002FB06
J 0
(2840 650);
DISPLAY 0.808511 (2840 650);
DISPLAY INVISIBLE (2840 650);
FORCEPROP 1 LAST TOLERANCE 1%
J 0
(2845 800);
DISPLAY 0.787234 (2845 800);
FORCEPROP 1 LAST VALUE 1K
J 0
(2845 850);
DISPLAY 0.787234 (2845 850);
FORCEPROP 1 LAST WATTAGE 1/16W
J 0
(2840 750);
DISPLAY 0.787234 (2840 750);
FORCEPROP 1 LAST MATERIAL CHIP
J 0
(2840 700);
DISPLAY 0.787234 (2840 700);
FORCEPROP 1 LAST PACK_TYPE 0402LF
J 0
(2840 600);
DISPLAY 0.787234 (2840 600);
FORCEPROP 1 LAST $LOCATION R379
J 0
(2845 900);
DISPLAY 0.978723 (2845 900);
FORCEPROP 1 LASTPIN (2800 875) $PN 1
J 0
(2805 837);
DISPLAY 0.787234 (2805 837);
FORCEPROP 1 LASTPIN (2800 675) $PN 2
J 0
(2805 685);
DISPLAY 0.787234 (2805 685);
FORCEPROP 1 LAST PATH I76
J 0
(2850 950);
DISPLAY 0.978723 (2850 950);
PAINT WHITE (2850 950);
DISPLAY INVISIBLE (2850 950);
FORCEPROP 2 LAST CDS_LIB pure_quanta
J 0
(2800 775);
PAINT MONO (2800 775);
DISPLAY INVISIBLE (2800 775);
FORCEPROP 2 LAST CDS_LOCATION R379
J 0
(2850 1000);
DISPLAY 1.021277 (2850 1000);
DISPLAY INVISIBLE (2850 1000);
FORCEPROP 2 LAST $SEC 1
J 0
(2850 1000);
DISPLAY 0.680851 (2850 1000);
PAINT MONO (2850 1000);
DISPLAY INVISIBLE (2850 1000);
FORCEPROP 2 LAST CDS_SEC 1
J 0
(2850 1000);
DISPLAY 1.021277 (2850 1000);
DISPLAY INVISIBLE (2850 1000);
FORCEADD Q_RES..2
(2800 1250);
FORCEPROP 1 LAST PART_NUMBER CS21002FB06
J 0
(2840 1125);
DISPLAY 0.787234 (2840 1125);
DISPLAY INVISIBLE (2840 1125);
FORCEPROP 1 LAST TOLERANCE 1%
J 0
(2845 1275);
DISPLAY 0.787234 (2845 1275);
FORCEPROP 1 LAST VALUE 1K
J 0
(2845 1325);
DISPLAY 0.787234 (2845 1325);
FORCEPROP 1 LAST WATTAGE 1/16W
J 0
(2840 1225);
DISPLAY 0.787234 (2840 1225);
FORCEPROP 1 LAST MATERIAL EMPTY
J 0
(2840 1175);
DISPLAY 0.787234 (2840 1175);
FORCEPROP 1 LAST PACK_TYPE 0402LF
J 0
(2840 1075);
DISPLAY 0.787234 (2840 1075);
FORCEPROP 1 LAST $LOCATION R378
J 0
(2845 1375);
DISPLAY 0.978723 (2845 1375);
FORCEPROP 1 LASTPIN (2800 1350) $PN 1
J 0
(2805 1312);
DISPLAY 0.787234 (2805 1312);
FORCEPROP 1 LASTPIN (2800 1150) $PN 2
J 0
(2805 1160);
DISPLAY 0.787234 (2805 1160);
FORCEPROP 1 LAST PATH I77
J 0
(2850 1425);
DISPLAY 0.978723 (2850 1425);
PAINT WHITE (2850 1425);
DISPLAY INVISIBLE (2850 1425);
FORCEPROP 2 LAST CDS_LIB pure_quanta
J 0
(2800 1250);
PAINT MONO (2800 1250);
DISPLAY INVISIBLE (2800 1250);
FORCEPROP 2 LAST CDS_LOCATION R378
J 0
(2850 1475);
DISPLAY 1.021277 (2850 1475);
DISPLAY INVISIBLE (2850 1475);
FORCEPROP 2 LAST $SEC 1
J 0
(2850 1475);
DISPLAY 0.680851 (2850 1475);
PAINT MONO (2850 1475);
DISPLAY INVISIBLE (2850 1475);
FORCEPROP 2 LAST CDS_SEC 1
J 0
(2850 1475);
DISPLAY 1.021277 (2850 1475);
DISPLAY INVISIBLE (2850 1475);
FORCEADD Q_RES..2
(2800 -775);
FORCEPROP 1 LAST PART_NUMBER CS21002FB06
J 0
(2840 -900);
DISPLAY 0.638298 (2840 -900);
DISPLAY INVISIBLE (2840 -900);
FORCEPROP 1 LAST TOLERANCE 1%
J 0
(2845 -750);
DISPLAY 0.787234 (2845 -750);
FORCEPROP 1 LAST PACK_TYPE 0402LF
J 0
(2840 -950);
DISPLAY 0.787234 (2840 -950);
FORCEPROP 1 LAST MATERIAL EMPTY
J 0
(2840 -850);
DISPLAY 0.787234 (2840 -850);
FORCEPROP 1 LAST VALUE 1K
J 0
(2845 -700);
DISPLAY 0.787234 (2845 -700);
FORCEPROP 1 LAST WATTAGE 1/16W
J 0
(2840 -800);
DISPLAY 0.787234 (2840 -800);
FORCEPROP 1 LAST $LOCATION R380
J 0
(2845 -650);
DISPLAY 0.978723 (2845 -650);
FORCEPROP 1 LASTPIN (2800 -675) $PN 1
J 0
(2805 -713);
DISPLAY 0.787234 (2805 -713);
FORCEPROP 1 LASTPIN (2800 -875) $PN 2
J 0
(2805 -865);
DISPLAY 0.787234 (2805 -865);
FORCEPROP 1 LAST PATH I78
J 0
(2850 -600);
DISPLAY 0.978723 (2850 -600);
PAINT WHITE (2850 -600);
DISPLAY INVISIBLE (2850 -600);
FORCEPROP 2 LAST CDS_LIB pure_quanta
J 0
(2800 -775);
PAINT MONO (2800 -775);
DISPLAY INVISIBLE (2800 -775);
FORCEPROP 2 LAST CDS_LOCATION R380
J 0
(2850 -550);
DISPLAY 1.021277 (2850 -550);
DISPLAY INVISIBLE (2850 -550);
FORCEPROP 2 LAST $SEC 1
J 0
(2850 -550);
DISPLAY 0.680851 (2850 -550);
PAINT MONO (2850 -550);
DISPLAY INVISIBLE (2850 -550);
FORCEPROP 2 LAST CDS_SEC 1
J 0
(2850 -550);
DISPLAY 1.021277 (2850 -550);
DISPLAY INVISIBLE (2850 -550);
FORCEADD OFFPAGE..2
(4050 -1050);
FORCEPROP 2 LAST $XR1 183 
J 0
(4359 -1050);
DISPLAY 0.638298 (4359 -1050);
PAINT MONO (4359 -1050);
FORCEPROP 2 LAST $XR0 201 
J 0
(4239 -1050);
DISPLAY 0.638298 (4239 -1050);
PAINT MONO (4239 -1050);
FORCEPROP 2 LAST PATH I79
J 0
(4225 -975);
DISPLAY 1.021277 (4225 -975);
DISPLAY INVISIBLE (4225 -975);
FORCEPROP 1 LAST COMMENT_BODY TRUE
J 0
(4005 -1145);
DISPLAY 0.872340 (4005 -1145);
PAINT GREEN (4005 -1145);
DISPLAY INVISIBLE (4005 -1145);
FORCEPROP 1 LAST OFFPAGE TRUE
J 0
(4375 -1175);
DISPLAY 0.872340 (4375 -1175);
DISPLAY INVISIBLE (4375 -1175);
FORCEPROP 2 LAST CDS_LIB standard
J 0
(4050 -1050);
PAINT MONO (4050 -1050);
DISPLAY INVISIBLE (4050 -1050);
FORCEADD OFFPAGE..2
(-2225 1000);
FORCEPROP 2 LAST $XR2 240 
J 0
(-1796 1000);
DISPLAY 0.638298 (-1796 1000);
PAINT MONO (-1796 1000);
FORCEPROP 2 LAST $XR1 214 
J 0
(-1916 1000);
DISPLAY 0.638298 (-1916 1000);
PAINT MONO (-1916 1000);
FORCEPROP 2 LAST $XR0 185 
J 0
(-2036 1000);
DISPLAY 0.638298 (-2036 1000);
PAINT MONO (-2036 1000);
FORCEPROP 2 LAST PATH I8
J 0
(-2050 1075);
DISPLAY 1.021277 (-2050 1075);
DISPLAY INVISIBLE (-2050 1075);
FORCEPROP 1 LAST COMMENT_BODY TRUE
J 0
(-2270 905);
DISPLAY 0.872340 (-2270 905);
PAINT GREEN (-2270 905);
DISPLAY INVISIBLE (-2270 905);
FORCEPROP 1 LAST OFFPAGE TRUE
J 0
(-1900 875);
DISPLAY 0.872340 (-1900 875);
DISPLAY INVISIBLE (-1900 875);
FORCEPROP 2 LAST CDS_LIB standard
J 0
(-2225 1000);
PAINT MONO (-2225 1000);
DISPLAY INVISIBLE (-2225 1000);
FORCEADD UNIVERSAL_POWER..1
(2800 -525);
FORCEPROP 3 LASTPIN (2800 -575) SIG_NAME P3V3_AUX\g
J 0
(2810 -565);
DISPLAY 0.659574 (2810 -565);
PAINT MONO (2810 -565);
DISPLAY INVISIBLE (2810 -565);
FORCEPROP 1 LAST HDL_POWER P3V3_AUX
J 1
(2800 -475);
DISPLAY 0.872340 (2800 -475);
PAINT GREEN (2800 -475);
FORCEPROP 1 LAST PATH I80
J 0
(2850 -500);
DISPLAY 0.872340 (2850 -500);
PAINT AQUA (2850 -500);
DISPLAY INVISIBLE (2850 -500);
FORCEPROP 2 LAST CDS_LIB logical_power
J 0
(2800 -525);
PAINT MONO (2800 -525);
DISPLAY INVISIBLE (2800 -525);
FORCEADD Q_RES..2
(2800 -1300);
FORCEPROP 1 LAST PART_NUMBER CS31002FB08
J 0
(2840 -1425);
DISPLAY 0.787234 (2840 -1425);
DISPLAY INVISIBLE (2840 -1425);
FORCEPROP 1 LAST VALUE 10K
J 0
(2845 -1225);
DISPLAY 0.787234 (2845 -1225);
FORCEPROP 1 LAST PACK_TYPE 0402LF
J 0
(2840 -1475);
DISPLAY 0.787234 (2840 -1475);
FORCEPROP 1 LAST MATERIAL CHIP
J 0
(2840 -1375);
DISPLAY 0.787234 (2840 -1375);
FORCEPROP 1 LAST WATTAGE 1/16W
J 0
(2840 -1325);
DISPLAY 0.787234 (2840 -1325);
FORCEPROP 1 LAST TOLERANCE 1%
J 0
(2845 -1275);
DISPLAY 0.787234 (2845 -1275);
FORCEPROP 1 LAST $LOCATION R381
J 0
(2845 -1175);
DISPLAY 0.978723 (2845 -1175);
FORCEPROP 1 LASTPIN (2800 -1200) $PN 1
J 0
(2805 -1238);
DISPLAY 0.787234 (2805 -1238);
FORCEPROP 1 LASTPIN (2800 -1400) $PN 2
J 0
(2805 -1390);
DISPLAY 0.787234 (2805 -1390);
FORCEPROP 1 LAST PATH I81
J 0
(2850 -1125);
DISPLAY 0.978723 (2850 -1125);
PAINT WHITE (2850 -1125);
DISPLAY INVISIBLE (2850 -1125);
FORCEPROP 2 LAST CDS_LIB pure_quanta
J 0
(2800 -1300);
PAINT MONO (2800 -1300);
DISPLAY INVISIBLE (2800 -1300);
FORCEPROP 2 LAST CDS_LOCATION R381
J 0
(2850 -1075);
DISPLAY 1.021277 (2850 -1075);
DISPLAY INVISIBLE (2850 -1075);
FORCEPROP 2 LAST $SEC 1
J 0
(2850 -1075);
DISPLAY 0.680851 (2850 -1075);
PAINT MONO (2850 -1075);
DISPLAY INVISIBLE (2850 -1075);
FORCEPROP 2 LAST CDS_SEC 1
J 0
(2850 -1075);
DISPLAY 1.021277 (2850 -1075);
DISPLAY INVISIBLE (2850 -1075);
FORCEADD UNIVERSAL_GND..1
(2800 -1525);
FORCEPROP 3 LASTPIN (2800 -1475) SIG_NAME GND\g
J 0
(2810 -1465);
DISPLAY 0.659574 (2810 -1465);
PAINT MONO (2810 -1465);
DISPLAY INVISIBLE (2810 -1465);
FORCEPROP 2 LAST ROOM IO_SLOT
J 1
(2575 -1450);
DISPLAY 0.744681 (2575 -1450);
DISPLAY INVISIBLE (2575 -1450);
FORCEPROP 1 LAST PATH I82
J 0
(2875 -1525);
DISPLAY 0.872340 (2875 -1525);
PAINT AQUA (2875 -1525);
DISPLAY INVISIBLE (2875 -1525);
FORCEPROP 1 LAST HDL_POWER GND
J 1
(2825 -1600);
DISPLAY 0.872340 (2825 -1600);
PAINT GREEN (2825 -1600);
DISPLAY INVISIBLE (2825 -1600);
FORCEPROP 2 LAST CDS_LIB logical_power
J 0
(2800 -1525);
PAINT MONO (2800 -1525);
DISPLAY INVISIBLE (2800 -1525);
FORCEADD OFFPAGE..2
(-2200 3000);
FORCEPROP 2 LAST $XR2 185 
J 0
(-1771 3000);
DISPLAY 0.638298 (-1771 3000);
PAINT MONO (-1771 3000);
FORCEPROP 2 LAST $XR1 205 
J 0
(-1891 3000);
DISPLAY 0.638298 (-1891 3000);
PAINT MONO (-1891 3000);
FORCEPROP 2 LAST $XR0 131 
J 0
(-2011 3000);
DISPLAY 0.638298 (-2011 3000);
PAINT MONO (-2011 3000);
FORCEPROP 2 LAST PATH I84
J 0
(-2000 3050);
DISPLAY 1.021277 (-2000 3050);
DISPLAY INVISIBLE (-2000 3050);
FORCEPROP 1 LAST COMMENT_BODY TRUE
J 0
(-2245 2905);
DISPLAY 0.872340 (-2245 2905);
PAINT GREEN (-2245 2905);
DISPLAY INVISIBLE (-2245 2905);
FORCEPROP 1 LAST OFFPAGE TRUE
J 0
(-1875 2875);
DISPLAY 0.872340 (-1875 2875);
DISPLAY INVISIBLE (-1875 2875);
FORCEPROP 2 LAST CDS_LIB standard
J 0
(-2200 3000);
PAINT MONO (-2200 3000);
DISPLAY INVISIBLE (-2200 3000);
FORCEADD UNIVERSAL_POWER..1
(-3450 3550);
FORCEPROP 3 LASTPIN (-3450 3500) SIG_NAME P3V3_AUX\g
J 0
(-3440 3510);
DISPLAY 0.659574 (-3440 3510);
PAINT MONO (-3440 3510);
DISPLAY INVISIBLE (-3440 3510);
FORCEPROP 1 LAST HDL_POWER P3V3_AUX
J 1
(-3450 3600);
DISPLAY 0.872340 (-3450 3600);
PAINT GREEN (-3450 3600);
FORCEPROP 1 LAST PATH I85
J 0
(-3400 3575);
DISPLAY 0.872340 (-3400 3575);
PAINT AQUA (-3400 3575);
DISPLAY INVISIBLE (-3400 3575);
FORCEPROP 2 LAST CDS_LIB logical_power
J 0
(-3450 3550);
PAINT MONO (-3450 3550);
DISPLAY INVISIBLE (-3450 3550);
FORCEADD UNIVERSAL_GND..1
(-3450 2550);
FORCEPROP 3 LASTPIN (-3450 2600) SIG_NAME GND\g
J 0
(-3440 2610);
DISPLAY 0.659574 (-3440 2610);
PAINT MONO (-3440 2610);
DISPLAY INVISIBLE (-3440 2610);
FORCEPROP 2 LAST ROOM IO_SLOT
J 1
(-3675 2625);
DISPLAY 0.744681 (-3675 2625);
DISPLAY INVISIBLE (-3675 2625);
FORCEPROP 1 LAST PATH I87
J 0
(-3375 2550);
DISPLAY 0.872340 (-3375 2550);
PAINT AQUA (-3375 2550);
DISPLAY INVISIBLE (-3375 2550);
FORCEPROP 1 LAST HDL_POWER GND
J 1
(-3425 2475);
DISPLAY 0.872340 (-3425 2475);
PAINT GREEN (-3425 2475);
DISPLAY INVISIBLE (-3425 2475);
FORCEPROP 2 LAST CDS_LIB logical_power
J 0
(-3450 2550);
PAINT MONO (-3450 2550);
DISPLAY INVISIBLE (-3450 2550);
FORCEADD Q_RES..2
(-3450 2775);
FORCEPROP 1 LAST PART_NUMBER CS21002FB06
J 0
(-3410 2650);
DISPLAY 0.787234 (-3410 2650);
DISPLAY INVISIBLE (-3410 2650);
FORCEPROP 1 LAST MATERIAL EMPTY
J 0
(-3410 2700);
DISPLAY 0.787234 (-3410 2700);
PAINT RED (-3410 2700);
FORCEPROP 1 LAST TOLERANCE 1%
J 0
(-3405 2800);
DISPLAY 0.787234 (-3405 2800);
FORCEPROP 1 LAST PACK_TYPE 0402LF
J 0
(-3410 2600);
DISPLAY 0.787234 (-3410 2600);
FORCEPROP 1 LAST WATTAGE 1/16W
J 0
(-3410 2750);
DISPLAY 0.787234 (-3410 2750);
FORCEPROP 1 LAST VALUE 1K
J 0
(-3405 2850);
DISPLAY 0.787234 (-3405 2850);
FORCEPROP 1 LAST $LOCATION R1810
J 0
(-3405 2900);
DISPLAY 0.978723 (-3405 2900);
FORCEPROP 1 LASTPIN (-3450 2875) $PN 1
J 0
(-3445 2837);
DISPLAY 0.787234 (-3445 2837);
FORCEPROP 1 LASTPIN (-3450 2675) $PN 2
J 0
(-3445 2685);
DISPLAY 0.787234 (-3445 2685);
FORCEPROP 1 LAST PATH I88
J 0
(-3400 2950);
DISPLAY 0.978723 (-3400 2950);
PAINT WHITE (-3400 2950);
DISPLAY INVISIBLE (-3400 2950);
FORCEPROP 2 LAST CDS_LIB pure_quanta
J 0
(-3450 2775);
PAINT MONO (-3450 2775);
DISPLAY INVISIBLE (-3450 2775);
FORCEPROP 2 LAST CDS_LOCATION R1810
J 0
(-3400 3000);
DISPLAY 1.021277 (-3400 3000);
DISPLAY INVISIBLE (-3400 3000);
FORCEPROP 2 LAST $SEC 1
J 0
(-3400 3000);
DISPLAY 0.680851 (-3400 3000);
PAINT MONO (-3400 3000);
DISPLAY INVISIBLE (-3400 3000);
FORCEPROP 2 LAST CDS_SEC 1
J 0
(-3400 3000);
DISPLAY 1.021277 (-3400 3000);
DISPLAY INVISIBLE (-3400 3000);
FORCEADD Q_RES..2
(-3450 3300);
FORCEPROP 1 LAST PART_NUMBER CS32002FB06
J 0
(-3410 3175);
DISPLAY 0.787234 (-3410 3175);
DISPLAY INVISIBLE (-3410 3175);
FORCEPROP 1 LAST VALUE 20K
J 0
(-3405 3375);
DISPLAY 0.787234 (-3405 3375);
FORCEPROP 1 LAST PACK_TYPE 0402LF
J 0
(-3410 3125);
DISPLAY 0.787234 (-3410 3125);
FORCEPROP 1 LAST MATERIAL CHIP
J 0
(-3410 3225);
DISPLAY 0.787234 (-3410 3225);
FORCEPROP 1 LAST WATTAGE 1/16W
J 0
(-3410 3275);
DISPLAY 0.787234 (-3410 3275);
FORCEPROP 1 LAST TOLERANCE 1%
J 0
(-3405 3325);
DISPLAY 0.787234 (-3405 3325);
FORCEPROP 1 LAST $LOCATION R1809
J 0
(-3405 3425);
DISPLAY 0.787234 (-3405 3425);
FORCEPROP 1 LASTPIN (-3450 3400) $PN 1
J 0
(-3445 3362);
DISPLAY 0.787234 (-3445 3362);
FORCEPROP 1 LASTPIN (-3450 3200) $PN 2
J 0
(-3445 3210);
DISPLAY 0.787234 (-3445 3210);
FORCEPROP 1 LAST PATH I89
J 0
(-3400 3475);
DISPLAY 0.978723 (-3400 3475);
PAINT WHITE (-3400 3475);
DISPLAY INVISIBLE (-3400 3475);
FORCEPROP 2 LAST CDS_LIB pure_quanta
J 0
(-3450 3300);
PAINT MONO (-3450 3300);
DISPLAY INVISIBLE (-3450 3300);
FORCEPROP 2 LAST CDS_LOCATION R1809
J 0
(-3400 3525);
DISPLAY 1.021277 (-3400 3525);
DISPLAY INVISIBLE (-3400 3525);
FORCEPROP 2 LAST $SEC 1
J 0
(-3400 3525);
DISPLAY 0.680851 (-3400 3525);
PAINT MONO (-3400 3525);
DISPLAY INVISIBLE (-3400 3525);
FORCEPROP 2 LAST CDS_SEC 1
J 0
(-3400 3525);
DISPLAY 1.021277 (-3400 3525);
DISPLAY INVISIBLE (-3400 3525);
FORCEADD Q_RES..2
(2825 2800);
FORCEPROP 1 LAST PART_NUMBER CS32002FB06
J 0
(2865 2675);
DISPLAY 0.638298 (2865 2675);
DISPLAY INVISIBLE (2865 2675);
FORCEPROP 1 LAST MATERIAL EMPTY
J 0
(2865 2725);
DISPLAY 0.787234 (2865 2725);
PAINT RED (2865 2725);
FORCEPROP 1 LAST WATTAGE 1/16W
J 0
(2865 2775);
DISPLAY 0.787234 (2865 2775);
FORCEPROP 1 LAST TOLERANCE 1%
J 0
(2870 2825);
DISPLAY 0.787234 (2870 2825);
FORCEPROP 1 LAST VALUE 20K
J 0
(2870 2875);
DISPLAY 0.787234 (2870 2875);
FORCEPROP 1 LAST PACK_TYPE 0402LF
J 0
(2865 2625);
DISPLAY 0.787234 (2865 2625);
FORCEPROP 1 LAST $LOCATION R1962
J 0
(2870 2925);
DISPLAY 0.978723 (2870 2925);
FORCEPROP 1 LASTPIN (2825 2900) $PN 1
J 0
(2830 2862);
DISPLAY 0.787234 (2830 2862);
PAINT MONO (2830 2862);
FORCEPROP 1 LASTPIN (2825 2700) $PN 2
J 0
(2830 2710);
DISPLAY 0.787234 (2830 2710);
PAINT MONO (2830 2710);
FORCEPROP 2 LAST CDS_LIB pure_quanta
J 0
(2825 2800);
DISPLAY INVISIBLE (2825 2800);
FORCEPROP 1 LAST PATH I90
J 0
(2875 2975);
DISPLAY 0.978723 (2875 2975);
PAINT WHITE (2875 2975);
DISPLAY INVISIBLE (2875 2975);
FORCEPROP 0 LAST CDS_LOCATION R1962
J 0
(2875 2975);
DISPLAY 1.021277 (2875 2975);
DISPLAY INVISIBLE (2875 2975);
FORCEPROP 0 LAST $SEC 1
J 0
(2875 2975);
DISPLAY 0.680851 (2875 2975);
PAINT MONO (2875 2975);
DISPLAY INVISIBLE (2875 2975);
FORCEPROP 0 LAST CDS_SEC 1
J 0
(2875 2975);
DISPLAY 1.021277 (2875 2975);
DISPLAY INVISIBLE (2875 2975);
FORCEADD UNIVERSAL_GND..1
(2825 2575);
FORCEPROP 3 LASTPIN (2825 2625) SIG_NAME GND\g
J 0
(2835 2635);
DISPLAY 0.659574 (2835 2635);
PAINT MONO (2835 2635);
DISPLAY INVISIBLE (2835 2635);
FORCEPROP 2 LAST ROOM IO_SLOT
J 1
(2600 2650);
DISPLAY 0.744681 (2600 2650);
DISPLAY INVISIBLE (2600 2650);
FORCEPROP 1 LAST PATH I91
J 0
(2900 2575);
DISPLAY 0.872340 (2900 2575);
PAINT AQUA (2900 2575);
DISPLAY INVISIBLE (2900 2575);
FORCEPROP 1 LAST HDL_POWER GND
J 1
(2850 2500);
DISPLAY 0.872340 (2850 2500);
PAINT GREEN (2850 2500);
DISPLAY INVISIBLE (2850 2500);
FORCEPROP 2 LAST CDS_LIB logical_power
J 0
(2825 2575);
DISPLAY INVISIBLE (2825 2575);
FORCEADD Q_RES..2
(-3475 775);
FORCEPROP 1 LAST PART_NUMBER CS31002FB08
J 0
(-3435 650);
DISPLAY 0.787234 (-3435 650);
DISPLAY INVISIBLE (-3435 650);
FORCEPROP 1 LAST PACK_TYPE 0402LF
J 0
(-3435 600);
DISPLAY 0.787234 (-3435 600);
FORCEPROP 1 LAST WATTAGE 1/16W
J 0
(-3435 750);
DISPLAY 0.787234 (-3435 750);
FORCEPROP 1 LAST MATERIAL CHIP
J 0
(-3435 700);
DISPLAY 0.787234 (-3435 700);
FORCEPROP 1 LAST VALUE 10K
J 0
(-3430 850);
DISPLAY 0.787234 (-3430 850);
FORCEPROP 1 LAST TOLERANCE 1%
J 0
(-3430 800);
DISPLAY 0.787234 (-3430 800);
FORCEPROP 1 LAST $LOCATION R3325
J 0
(-3430 900);
DISPLAY 0.978723 (-3430 900);
FORCEPROP 1 LASTPIN (-3475 875) $PN 1
J 0
(-3470 837);
DISPLAY 0.787234 (-3470 837);
PAINT MONO (-3470 837);
FORCEPROP 1 LASTPIN (-3475 675) $PN 2
J 0
(-3470 685);
DISPLAY 0.787234 (-3470 685);
PAINT MONO (-3470 685);
FORCEPROP 1 LAST PATH I92
J 0
(-3425 950);
DISPLAY 0.978723 (-3425 950);
PAINT WHITE (-3425 950);
DISPLAY INVISIBLE (-3425 950);
FORCEPROP 2 LAST CDS_LIB pure_quanta
J 0
(-3475 775);
DISPLAY INVISIBLE (-3475 775);
FORCEPROP 0 LAST CDS_LOCATION R3325
J 0
(-3425 950);
DISPLAY 1.021277 (-3425 950);
DISPLAY INVISIBLE (-3425 950);
FORCEPROP 0 LAST $SEC 1
J 0
(-3425 950);
DISPLAY 0.680851 (-3425 950);
PAINT MONO (-3425 950);
DISPLAY INVISIBLE (-3425 950);
FORCEPROP 0 LAST CDS_SEC 1
J 0
(-3425 950);
DISPLAY 1.021277 (-3425 950);
DISPLAY INVISIBLE (-3425 950);
FORCEADD UNIVERSAL_GND..1
(-3475 550);
FORCEPROP 3 LASTPIN (-3475 600) SIG_NAME GND\g
J 0
(-3465 610);
DISPLAY 0.659574 (-3465 610);
PAINT MONO (-3465 610);
DISPLAY INVISIBLE (-3465 610);
FORCEPROP 2 LAST ROOM IO_SLOT
J 1
(-3700 625);
DISPLAY 0.744681 (-3700 625);
DISPLAY INVISIBLE (-3700 625);
FORCEPROP 1 LAST PATH I93
J 0
(-3400 550);
DISPLAY 0.872340 (-3400 550);
PAINT AQUA (-3400 550);
DISPLAY INVISIBLE (-3400 550);
FORCEPROP 1 LAST HDL_POWER GND
J 1
(-3450 475);
DISPLAY 0.872340 (-3450 475);
PAINT GREEN (-3450 475);
DISPLAY INVISIBLE (-3450 475);
FORCEPROP 2 LAST CDS_LIB logical_power
J 0
(-3475 550);
DISPLAY INVISIBLE (-3475 550);
FORCEADD QUANTA_TITLE_BLOCK_C..1
(5075 -2075);
FORCEPROP 0 LAST CDS_CON_LAST_MODIFIED Fri Aug 25 14:03:12 2023
J 0
(3190 -2060);
PAINT MONO (3190 -2060);
DISPLAY INVISIBLE (3190 -2060);
FORCEPROP 2 LAST CUSTOM_TXT_CDS <XR_PAGE_TITLE>
J 0
(-2815 3175);
DISPLAY 0.638298 (-2815 3175);
PAINT PINK (-2815 3175);
DISPLAY INVISIBLE (-2815 3175);
FORCEPROP 2 LAST CUSTOM_TXT_CDS <CON_LAST_MODIFIED>
J 0
(3190 -2060);
DISPLAY 0.978723 (3190 -2060);
FORCEPROP 2 LAST CUSTOM_TXT_CDS <NAME_1>
J 0
(1900 -1900);
FORCEPROP 2 LAST CUSTOM_TXT_CDS <NAME_2>
J 0
(1900 -2025);
FORCEPROP 2 LAST CUSTOM_TXT_CDS <Q_PROJ>
J 0
(2693 -1973);
DISPLAY 1.212766 (2693 -1973);
FORCEPROP 2 LAST CUSTOM_TXT_CDS <Q_NUMBER>
J 0
(3672 -1972);
DISPLAY 1.212766 (3672 -1972);
FORCEPROP 2 LAST CUSTOM_TXT_CDS <CON_PAGE_NUM> OF <CON_TOTAL_PAGES>
J 0
(4629 -2057);
DISPLAY 0.978723 (4629 -2057);
FORCEPROP 2 LAST CUSTOM_TXT_CDS <Q_REV>
J 0
(4891 -1972);
DISPLAY 1.212766 (4891 -1972);
FORCEPROP 1 LAST Q_TITLE PCH SIDEBAND: HW STRAPS (1/4)
J 0
(-4266 -2049);
DISPLAY 1.957447 (-4266 -2049);
PAINT GREEN (-4266 -2049);
FORCEPROP 1 LAST Q_DEPT 
J 1
(1312 -2026);
DISPLAY 1.957447 (1312 -2026);
PAINT GREEN (1312 -2026);
FORCEPROP 2 LAST CDS_XR_PAGE_TITLE CR-198 : @S9S_MB_2U_LIB.S9S_MB_2U(SCH_1):PAGE198
J 0
(-2815 3175);
DISPLAY 0.638298 (-2815 3175);
PAINT PINK (-2815 3175);
DISPLAY INVISIBLE (-2815 3175);
FORCEPROP 2 LAST CDS_LIB pure_quanta
J 0
(5075 -2075);
PAINT MONO (5075 -2075);
DISPLAY INVISIBLE (5075 -2075);
FORCEPROP 1 LAST CDS_LMAN_SYM_OUTLINE -9475,6775,100,-125
J 0
(5075 -2075);
DISPLAY 0.468085 (5075 -2075);
PAINT GREEN (5075 -2075);
DISPLAY INVISIBLE (5075 -2075);
FORCEPROP 2 LAST PAGE_BORDER TRUE
J 0
(-2815 3175);
DISPLAY 0.638298 (-2815 3175);
PAINT PINK (-2815 3175);
DISPLAY INVISIBLE (-2815 3175);
FORCEPROP 1 LAST COMMENT_BODY TRUE
J 0
(5087 -2088);
DISPLAY 0.978723 (5087 -2088);
PAINT GREEN (5087 -2088);
DISPLAY INVISIBLE (5087 -2088);
FORCEADD DNS..2
(-350 -825);
PAINT RED (-350 -825);
FORCEPROP 1 LAST COMMENT_BODY TRUE
J 0
(-350 -825);
DISPLAY INVISIBLE (-350 -825);
FORCEPROP 2 LAST CDS_LIB mstr_misc
J 0
(-350 -825);
DISPLAY INVISIBLE (-350 -825);
FORCEADD DNS..2
(2800 1225);
PAINT RED (2800 1225);
FORCEPROP 1 LAST COMMENT_BODY TRUE
J 0
(2800 1225);
DISPLAY INVISIBLE (2800 1225);
FORCEPROP 2 LAST CDS_LIB mstr_misc
J 0
(2800 1225);
PAINT MONO (2800 1225);
DISPLAY INVISIBLE (2800 1225);
FORCEADD DESIGN_NOTE..1
(3400 3550);
FORCEPROP 0 LAST S1 FOR POWER ON REQUEST, SET TO PD TO GND
J 0
(3200 3400);
DISPLAY 0.808511 (3200 3400);
PAINT SKYBLUE (3200 3400);
FORCEPROP 1 LAST COMMENT_BODY TRUE
J 0
(3425 3650);
DISPLAY 0.978723 (3425 3650);
DISPLAY INVISIBLE (3425 3650);
FORCEPROP 2 LAST CDS_LIB logical_power
J 0
(3400 3550);
DISPLAY INVISIBLE (3400 3550);
FORCEADD DNS..2
(2805 -805);
PAINT RED (2805 -805);
FORCEPROP 1 LAST COMMENT_BODY TRUE
J 0
(2805 -805);
DISPLAY INVISIBLE (2805 -805);
FORCEPROP 2 LAST CDS_LIB mstr_misc
J 0
(2805 -805);
PAINT MONO (2805 -805);
DISPLAY INVISIBLE (2805 -805);
FORCEADD DNS..2
(-345 3270);
PAINT RED (-345 3270);
FORCEPROP 1 LAST COMMENT_BODY TRUE
J 0
(-345 3270);
DISPLAY INVISIBLE (-345 3270);
FORCEPROP 2 LAST CDS_LIB mstr_misc
J 0
(-345 3270);
PAINT MONO (-345 3270);
DISPLAY INVISIBLE (-345 3270);
FORCEADD DNS..2
(-3445 2745);
PAINT RED (-3445 2745);
FORCEPROP 1 LAST COMMENT_BODY TRUE
J 0
(-3445 2745);
DISPLAY INVISIBLE (-3445 2745);
FORCEPROP 2 LAST CDS_LIB mstr_misc
J 0
(-3445 2745);
PAINT MONO (-3445 2745);
DISPLAY INVISIBLE (-3445 2745);
FORCEADD DNS..2
(-3450 1275);
PAINT RED (-3450 1275);
FORCEPROP 1 LAST COMMENT_BODY TRUE
J 0
(-3450 1275);
DISPLAY INVISIBLE (-3450 1275);
FORCEPROP 2 LAST CDS_LIB mstr_misc
J 0
(-3450 1275);
DISPLAY INVISIBLE (-3450 1275);
FORCEADD DNS..2
(2825 2775);
PAINT RED (2825 2775);
FORCEPROP 2 LAST CDS_LIB mstr_misc
J 0
(2825 2775);
DISPLAY INVISIBLE (2825 2775);
FORCEPROP 1 LAST COMMENT_BODY TRUE
J 0
(2825 2775);
DISPLAY INVISIBLE (2825 2775);
WIRE 16 -1 (-3475 1375)(-3475 1475);
WIRE 16 -1 (-3475 -700)(-3475 -600);
WIRE 16 -1 (-350 3400)(-350 3500);
WIRE 16 -1 (-350 -700)(-350 -600);
WIRE 16 -1 (2800 1350)(2800 1450);
WIRE 16 -1 (2800 -675)(2800 -575);
WIRE 16 -1 (-3450 3400)(-3450 3500);
WIRE 16 -1 (2825 3350)(2825 3450);
WIRE 16 -1 (-350 -1450)(-350 -1375);
WIRE 16 -1 (2800 600)(2800 675);
WIRE 16 -1 (2800 -1475)(2800 -1400);
WIRE 16 -1 (-3450 2600)(-3450 2675);
WIRE 16 -1 (2825 2625)(2825 2700);
WIRE 16 -1 (-350 2600)(-350 2675);
WIRE 16 -1 (-3475 600)(-3475 675);
WIRE 16 273 (2100 -1625)(2100 4275);
WIRE 16 -1 (2825 3000)(2825 2900);
WIRE 16 -1 (2825 3150)(2825 3000);
WIRE 16 -1 (4025 3000)(2825 3000);
FORCEPROP 2 LAST SIG_NAME FM_PCH_CONSENT_STRAP_N
J 0
(3015 3010);
DISPLAY 0.808511 (3015 3010);
PAINT WHITE (3015 3010);
WIRE 16 273 (-4050 2400)(4750 2400);
WIRE 16 273 (-1250 4225)(-1250 -1625);
WIRE 16 273 (4750 325)(-4050 325);
WIRE 16 -1 (-3475 -900)(-3475 -1050);
WIRE 16 -1 (-2275 -1050)(-3475 -1050);
FORCEPROP 2 LAST SIG_NAME FM_ADR_ACK
J 0
(-3185 -1040);
DISPLAY 0.808511 (-3185 -1040);
PAINT WHITE (-3185 -1040);
WIRE 16 -1 (-3475 1000)(-3475 875);
WIRE 16 -1 (-3475 1175)(-3475 1000);
WIRE 16 -1 (-2275 1000)(-3475 1000);
FORCEPROP 2 LAST SIG_NAME FM_PCH_SPKR
J 0
(-3335 1010);
DISPLAY 0.808511 (-3335 1010);
PAINT WHITE (-3335 1010);
WIRE 16 3135 (-2725 2625)(-2725 2500);
WIRE 16 3135 (-2725 2750)(-2725 2625);
WIRE 16 3135 (-2725 2500)(-2575 2500);
WIRE 16 3135 (-2575 2500)(-1475 2500);
WIRE 16 3135 (-2575 2625)(-2575 2500);
WIRE 16 3135 (-2575 2625)(-2725 2625);
WIRE 16 3135 (-2575 2750)(-2725 2750);
WIRE 16 3135 (-2575 2750)(-2575 2625);
WIRE 16 3135 (-1475 2750)(-2575 2750);
WIRE 16 3135 (-1475 2625)(-2575 2625);
WIRE 16 3135 (-1475 2500)(-1475 2625);
WIRE 16 3135 (-1475 2625)(-1475 2750);
WIRE 16 -1 (-350 3000)(-350 2875);
WIRE 16 -1 (-350 3200)(-350 3000);
WIRE 16 -1 (-350 3000)(850 3000);
FORCEPROP 2 LAST SIG_NAME FM_PCH_BOOT_BIOS_STRAP
J 0
(-160 3010);
DISPLAY 0.808511 (-160 3010);
PAINT WHITE (-160 3010);
WIRE 16 -1 (-3450 3000)(-3450 2875);
WIRE 16 -1 (-3450 3200)(-3450 3000);
WIRE 16 -1 (-3450 3000)(-2250 3000);
FORCEPROP 2 LAST SIG_NAME FM_ADR_MODE0
J 0
(-3260 3010);
DISPLAY 0.808511 (-3260 3010);
PAINT WHITE (-3260 3010);
WIRE 16 -1 (2800 -875)(2800 -1050);
WIRE 16 -1 (2800 -1050)(4000 -1050);
FORCEPROP 2 LAST SIG_NAME FM_FLASH_SECURITY_STRAP
J 0
(2990 -1040);
DISPLAY 0.808511 (2990 -1040);
PAINT WHITE (2990 -1040);
WIRE 16 -1 (2800 -1200)(2800 -1050);
WIRE 16 -1 (2800 1000)(2800 875);
WIRE 16 -1 (2800 1150)(2800 1000);
WIRE 16 -1 (2800 1000)(4025 1000);
FORCEPROP 2 LAST SIG_NAME FM_ADR_MODE1
J 0
(2990 1010);
DISPLAY 0.808511 (2990 1010);
PAINT WHITE (2990 1010);
WIRE 16 -1 (-350 -1050)(-350 -1175);
WIRE 16 -1 (-350 -900)(-350 -1050);
WIRE 16 -1 (850 -1050)(-350 -1050);
FORCEPROP 2 LAST SIG_NAME FM_SPI_3V3_1V8_VOLTAGE
J 0
(-160 -1040);
DISPLAY 0.808511 (-160 -1040);
PAINT WHITE (-160 -1040);
WIRE 16 3135 (400 -1450)(400 -1575);
WIRE 16 3135 (400 -1325)(400 -1450);
WIRE 16 3135 (400 -1575)(550 -1575);
WIRE 16 3135 (550 -1575)(2000 -1575);
WIRE 16 3135 (550 -1450)(400 -1450);
WIRE 16 3135 (550 -1450)(550 -1575);
WIRE 16 3135 (550 -1325)(400 -1325);
WIRE 16 3135 (550 -1450)(550 -1325);
WIRE 16 3135 (2000 -1325)(550 -1325);
WIRE 16 3135 (2000 -1450)(550 -1450);
WIRE 16 3135 (2000 -1575)(2000 -1450);
WIRE 16 3135 (2000 -1450)(2000 -1325);
WIRE 16 3135 (4950 775)(3725 775);
WIRE 16 3135 (4950 650)(4950 775);
WIRE 16 3135 (3725 775)(3575 775);
WIRE 16 3135 (3575 775)(3575 650);
WIRE 16 3135 (4950 525)(4950 650);
WIRE 16 3135 (3725 775)(3725 650);
WIRE 16 3135 (4950 650)(3725 650);
WIRE 16 3135 (3725 650)(3575 650);
WIRE 16 3135 (3725 650)(3725 525);
WIRE 16 3135 (3725 525)(4950 525);
WIRE 16 3135 (3575 650)(3575 525);
WIRE 16 3135 (3575 525)(3725 525);
DOT 1 (2825 3000);
DOT 1 (2800 1000);
DOT 1 (3575 650);
DOT 1 (3725 775);
DOT 1 (4950 650);
DOT 1 (-3450 3000);
DOT 1 (2800 -1050);
DOT 1 (-350 -1050);
DOT 1 (-350 3000);
DOT 1 (-2575 2625);
DOT 1 (-2575 2500);
DOT 1 (-2575 2750);
DOT 1 (-1475 2625);
DOT 1 (3725 525);
DOT 1 (3725 650);
DOT 1 (2000 -1450);
DOT 1 (550 -1575);
DOT 1 (550 -1450);
DOT 1 (550 -1325);
DOT 1 (400 -1450);
DOT 1 (-3475 1000);
DOT 1 (-2725 2625);
FORCENOTE
PCH INTERNAL: PULL DOWN
(-3635 1819) 0;
DISPLAY LEFT (-3635 1819);
DISPLAY 1.276596 (-3635 1819);
PAINT YELLOW (-3635 1819);
FORCENOTE
PCH INTERNAL: NO INTERNAL TERMICATION
(-3610 3819) 0;
DISPLAY LEFT (-3610 3819);
DISPLAY 1.276596 (-3610 3819);
PAINT YELLOW (-3610 3819);
FORCENOTE
FUNCTION:BOOT HALT STRAP
(-3610 4019) 0;
DISPLAY LEFT (-3610 4019);
DISPLAY 1.276596 (-3610 4019);
PAINT YELLOW (-3610 4019);
FORCENOTE
PCH INTERNAL: PULL DOWN
(2665 3819) 0;
DISPLAY LEFT (2665 3819);
DISPLAY 1.276596 (2665 3819);
PAINT YELLOW (2665 3819);
FORCENOTE
PCH INTERNAL: PULL DOWN
(2640 -256) 0;
DISPLAY LEFT (2640 -256);
DISPLAY 1.276596 (2640 -256);
PAINT YELLOW (2640 -256);
FORCENOTE
DEFAULT: 0 (ENABLE)
(2640 -156) 0;
DISPLAY LEFT (2640 -156);
DISPLAY 1.276596 (2640 -156);
PAINT YELLOW (2640 -156);
FORCENOTE
PD  A0 DEBUG IS ENABLED (DEFAULT) 
(3625 700) 0;
DISPLAY LEFT (3625 700);
DISPLAY 0.808511 (3625 700);
PAINT YELLOW (3625 700);
FORCENOTE
GROUP: GPPC_C_18
(2640 2119) 0;
DISPLAY LEFT (2640 2119);
DISPLAY 1.276596 (2640 2119);
PAINT YELLOW (2640 2119);
FORCENOTE
DEFAULT: 1 (DISABLE)
(2665 3919) 0;
DISPLAY LEFT (2665 3919);
DISPLAY 1.276596 (2665 3919);
PAINT YELLOW (2665 3919);
FORCENOTE
FUNCTION:CONSENT STRAP
(2665 4019) 0;
DISPLAY LEFT (2665 4019);
DISPLAY 1.276596 (2665 4019);
PAINT YELLOW (2665 4019);
FORCENOTE
GROUP: GPPC_S_5
(2665 4119) 0;
DISPLAY LEFT (2665 4119);
DISPLAY 1.276596 (2665 4119);
PAINT YELLOW (2665 4119);
FORCENOTE
PU  BOOT HALT DISABLE(DEFAULT)
(-2675 2550) 0;
DISPLAY LEFT (-2675 2550);
DISPLAY 0.808511 (-2675 2550);
PAINT YELLOW (-2675 2550);
FORCENOTE
PCH INTERNAL: PULL UP
(2640 1819) 0;
DISPLAY LEFT (2640 1819);
DISPLAY 1.276596 (2640 1819);
PAINT YELLOW (2640 1819);
FORCENOTE
DEFAULT: 0 (A0 DEBUG IS ENABLED)
(2640 1919) 0;
DISPLAY LEFT (2640 1919);
DISPLAY 1.276596 (2640 1919);
PAINT YELLOW (2640 1919);
FORCENOTE
GROUP: GPPC_S_1
(-3635 2119) 0;
DISPLAY LEFT (-3635 2119);
DISPLAY 1.276596 (-3635 2119);
PAINT YELLOW (-3635 2119);
FORCENOTE
DEFAULT: 1 (ENABLE)
(-3635 -156) 0;
DISPLAY LEFT (-3635 -156);
DISPLAY 1.276596 (-3635 -156);
PAINT YELLOW (-3635 -156);
FORCENOTE
DEFAULT: 0 (DISABLE)
(-510 3919) 0;
DISPLAY LEFT (-510 3919);
DISPLAY 1.276596 (-510 3919);
PAINT YELLOW (-510 3919);
FORCENOTE
GROUP: GPP_D_23
(-510 4119) 0;
DISPLAY LEFT (-510 4119);
DISPLAY 1.276596 (-510 4119);
PAINT YELLOW (-510 4119);
FORCENOTE
GROUP: GPPC_S_3
(-3610 4119) 0;
DISPLAY LEFT (-3610 4119);
DISPLAY 1.276596 (-3610 4119);
PAINT YELLOW (-3610 4119);
FORCENOTE
DEFAULT: 1 (DISABLE)
(-3610 3919) 0;
DISPLAY LEFT (-3610 3919);
DISPLAY 1.276596 (-3610 3919);
PAINT YELLOW (-3610 3919);
FORCENOTE
FUNCTION:PERSONALITY STRAP
(2640 2019) 0;
DISPLAY LEFT (2640 2019);
DISPLAY 1.276596 (2640 2019);
PAINT YELLOW (2640 2019);
FORCENOTE
GROUP: GPP_D_6
(2640 44) 0;
DISPLAY LEFT (2640 44);
DISPLAY 1.276596 (2640 44);
PAINT YELLOW (2640 44);
FORCENOTE
FUNCTION:FLASH SECURITY STRAP
(2640 -56) 0;
DISPLAY LEFT (2640 -56);
DISPLAY 1.276596 (2640 -56);
PAINT YELLOW (2640 -56);
FORCENOTE
PU  A0 DEBUG IS DISABLED 
(3625 575) 0;
DISPLAY LEFT (3625 575);
DISPLAY 0.808511 (3625 575);
PAINT YELLOW (3625 575);
FORCENOTE
FUNCTION:SPI BUFFER VOLTAGE
(-510 -56) 0;
DISPLAY LEFT (-510 -56);
DISPLAY 1.276596 (-510 -56);
PAINT YELLOW (-510 -56);
FORCENOTE
PD  SPI BUFFER VOLTAGE IS 3.3V (DEFAULT)
(450 -1400) 0;
DISPLAY LEFT (450 -1400);
DISPLAY 0.808511 (450 -1400);
PAINT YELLOW (450 -1400);
FORCENOTE
PU  SPI BUFFER VOLTAGE IS 1.8V  
(450 -1525) 0;
DISPLAY LEFT (450 -1525);
DISPLAY 0.808511 (450 -1525);
PAINT YELLOW (450 -1525);
FORCENOTE
DEFAULT: 0 (SET TO P3V3)
(-525 -150) 0;
DISPLAY LEFT (-525 -150);
DISPLAY 1.276596 (-525 -150);
PAINT YELLOW (-525 -150);
FORCENOTE
GROUP: GPPC_S_4
(-510 44) 0;
DISPLAY LEFT (-510 44);
DISPLAY 1.276596 (-510 44);
PAINT YELLOW (-510 44);
FORCENOTE
PD  BOOT HALT ENABLE
(-2675 2675) 0;
DISPLAY LEFT (-2675 2675);
DISPLAY 0.808511 (-2675 2675);
PAINT YELLOW (-2675 2675);
FORCENOTE
FUNCTION:BOOT BIOS STRAP
(-510 4019) 0;
DISPLAY LEFT (-510 4019);
DISPLAY 1.276596 (-510 4019);
PAINT YELLOW (-510 4019);
FORCENOTE
PCH INTERNAL: PULL DOWN
(-510 3819) 0;
DISPLAY LEFT (-510 3819);
DISPLAY 1.276596 (-510 3819);
PAINT YELLOW (-510 3819);
FORCENOTE
FUNCTION:NO REBOOT
(-3635 2019) 0;
DISPLAY LEFT (-3635 2019);
DISPLAY 1.276596 (-3635 2019);
PAINT YELLOW (-3635 2019);
FORCENOTE
DEFAULT: 0 (DISABLE)
(-3635 1919) 0;
DISPLAY LEFT (-3635 1919);
DISPLAY 1.276596 (-3635 1919);
PAINT YELLOW (-3635 1919);
FORCENOTE
PCH INTERNAL: 20KOHM PULL DOWN
(-510 -256) 0;
DISPLAY LEFT (-510 -256);
DISPLAY 1.276596 (-510 -256);
PAINT YELLOW (-510 -256);
FORCENOTE
GROUP: GPP_D_16
(-3635 44) 0;
DISPLAY LEFT (-3635 44);
DISPLAY 1.276596 (-3635 44);
PAINT YELLOW (-3635 44);
FORCENOTE
PCH INTERNAL: PULL DOWN
(-3635 -256) 0;
DISPLAY LEFT (-3635 -256);
DISPLAY 1.276596 (-3635 -256);
PAINT YELLOW (-3635 -256);
FORCENOTE
FUNCTION:TLS CONFIDENTIALITY
(-3635 -56) 0;
DISPLAY LEFT (-3635 -56);
DISPLAY 1.276596 (-3635 -56);
PAINT YELLOW (-3635 -56);
FORCENOTE
20210929 MODIFY FOR GT
(-3000 450) 0;
DISPLAY LEFT (-3000 450);
DISPLAY 1.595745 (-3000 450);
PAINT PINK (-3000 450);
FORCENOTE
20220727 POP R502,DEPOP R1962
(2925 2450) 0;
DISPLAY LEFT (2925 2450);
DISPLAY 1.276596 (2925 2450);
PAINT PINK (2925 2450);
QUIT
